# T6G (Grand Teton) — schematic netlist excerpt (pin names and nets, part order shuffled) for the footprints in the layout excerpt that follows; sources: Cadence DE-HDL packaged netlist, KiCad conversion of 04192023_DAF0TMB3IC0_F0TG_MB_C_brd_V02_OCP.brd

PC6515  Q_CAP  150PF 50V 5% NPO  pkg 0402  page 360 : A = P1V8_RETIMER_CPU0_FB ; B = P1V8_CPU0_RT_1D
R1191  Q_RES  0 5% CHIP  pkg 0402LF  page 140 : A = HP_LVC3_OCP_V3_2_PRSNT2_N_R ; B = HP_LVC3_OCP_V3_2_PRSNT2_N

(kicad_pcb
	(version 20260206)
	(generator "pcbnew")
	(generator_version "10.0")
	(general
		(thickness 1.6)
		(legacy_teardrops no)
	)
	(paper "A4")
	(title_block
		(title "04192023_DAF0TMB3IC0_F0TG_MB_C_brd_V02_OCP.brd")
		(comment 1 "Grand Teton / footprints 3696-3697 of 8354")
	)
	(layers
		(0 "F.Cu" signal "TOP")
		(4 "In1.Cu" signal "GND")
		(6 "In2.Cu" signal "IN1")
		(8 "In3.Cu" signal "GND1")
		(10 "In4.Cu" signal "IN2")
		(12 "In5.Cu" signal "GND2")
		(14 "In6.Cu" signal "IN3")
		(16 "In7.Cu" signal "GND3")
		(18 "In8.Cu" signal "VCC")
		(20 "In9.Cu" signal "VCC1")
		(22 "In10.Cu" signal "GND4")
		(24 "In11.Cu" signal "IN4")
		(26 "In12.Cu" signal "GND5")
		(28 "In13.Cu" signal "IN5")
		(30 "In14.Cu" signal "GND6")
		(32 "In15.Cu" signal "IN6")
		(34 "In16.Cu" signal "GND7")
		(2 "B.Cu" signal "BOTTOM")
		(9 "F.Adhes" user "F.Adhesive")
		(11 "B.Adhes" user "B.Adhesive")
		(13 "F.Paste" user "Package Geometry/Pastemask Top")
		(15 "B.Paste" user "Package Geometry/Pastemask Bottom")
		(5 "F.SilkS" user "Ref Des/Silkscreen Top")
		(7 "B.SilkS" user "Ref Des/Silkscreen Bottom")
		(1 "F.Mask" user "Board Geometry/Soldermask Top")
		(3 "B.Mask" user "Board Geometry/Soldermask Bottom")
		(17 "Dwgs.User" user "User.Drawings")
		(19 "Cmts.User" user "User.Comments")
		(21 "Eco1.User" user "User.Eco1")
		(23 "Eco2.User" user "User.Eco2")
		(25 "Edge.Cuts" user "Board Geometry/Outline")
		(27 "Margin" user)
		(31 "F.CrtYd" user "Package Geometry/Place Bound Top")
		(29 "B.CrtYd" user "Package Geometry/Place Bound Bottom")
		(35 "F.Fab" user "Ref Des/Assembly Top")
		(33 "B.Fab" user "Ref Des/Assembly Bottom")
	)
	(footprint ""
		(layer "F.Cu")
		(at 237.843822 -290.341812 90)
		(property "Reference" "PC6515"
			(at 0 0 90)
			(layer "F.SilkS")
			(hide yes)
			(effects
				(font
					(size 1.27 1.27)
				)
			)
		)
		(property "Value" ""
			(at 0 0 90)
			(layer "F.Fab")
			(effects
				(font
					(size 1.27 1.27)
				)
			)
		)
		(duplicate_pad_numbers_are_jumpers no)
		(fp_line
			(start 0.7874 -0.4064)
			(end 0.7874 0.4064)
			(stroke
				(width 0.1524)
				(type default)
			)
			(layer "F.SilkS")
		)
		(fp_line
			(start -0.7874 -0.4064)
			(end 0.7874 -0.4064)
			(stroke
				(width 0.1524)
				(type default)
			)
			(layer "F.SilkS")
		)
		(fp_line
			(start 0.7874 0.4064)
			(end -0.7874 0.4064)
			(stroke
				(width 0.1524)
				(type default)
			)
			(layer "F.SilkS")
		)
		(fp_line
			(start -0.7874 0.4064)
			(end -0.7874 -0.4064)
			(stroke
				(width 0.1524)
				(type default)
			)
			(layer "F.SilkS")
		)
		(fp_line
			(start -0.12065 -0.305054)
			(end -0.12065 -0.2794)
			(stroke
				(width 0.1)
				(type default)
			)
			(layer "F.Fab")
		)
		(fp_line
			(start -0.67945 -0.305054)
			(end -0.12065 -0.305054)
			(stroke
				(width 0.1)
				(type default)
			)
			(layer "F.Fab")
		)
		(fp_line
			(start 0.67945 -0.3048)
			(end 0.67945 0.3048)
			(stroke
				(width 0.1)
				(type default)
			)
			(layer "F.Fab")
		)
		(fp_line
			(start 0.12065 -0.3048)
			(end 0.67945 -0.3048)
			(stroke
				(width 0.1)
				(type default)
			)
			(layer "F.Fab")
		)
		(fp_line
			(start 0.12065 -0.2794)
			(end 0.12065 -0.3048)
			(stroke
				(width 0.1)
				(type default)
			)
			(layer "F.Fab")
		)
		(fp_line
			(start -0.12065 -0.2794)
			(end 0.12065 -0.2794)
			(stroke
				(width 0.1)
				(type default)
			)
			(layer "F.Fab")
		)
		(fp_line
			(start 0.120396 0.2794)
			(end -0.12065 0.2794)
			(stroke
				(width 0.1)
				(type default)
			)
			(layer "F.Fab")
		)
		(fp_line
			(start -0.12065 0.2794)
			(end -0.12065 0.3048)
			(stroke
				(width 0.1)
				(type default)
			)
			(layer "F.Fab")
		)
		(fp_line
			(start 0.67945 0.3048)
			(end 0.120396 0.3048)
			(stroke
				(width 0.1)
				(type default)
			)
			(layer "F.Fab")
		)
		(fp_line
			(start 0.120396 0.3048)
			(end 0.120396 0.2794)
			(stroke
				(width 0.1)
				(type default)
			)
			(layer "F.Fab")
		)
		(fp_line
			(start -0.12065 0.3048)
			(end -0.67945 0.3048)
			(stroke
				(width 0.1)
				(type default)
			)
			(layer "F.Fab")
		)
		(fp_line
			(start -0.67945 0.3048)
			(end -0.67945 -0.305054)
			(stroke
				(width 0.1)
				(type default)
			)
			(layer "F.Fab")
		)
		(pad "1" smd circle
			(at -0.40005 0 90)
			(size 0 0)
			(layers "F.Cu" "F.Mask" "F.Paste")
			(net "P1V8_RETIMER_CPU0_FB")
		)
		(pad "2" smd circle
			(at 0.40005 0 90)
			(size 0 0)
			(layers "F.Cu" "F.Mask" "F.Paste")
			(net "P1V8_CPU0_RT_1D")
		)
	)
	(footprint ""
		(layer "F.Cu")
		(at 15.55115 -68.128642)
		(property "Reference" "R1191"
			(at 0 0 0)
			(layer "F.SilkS")
			(hide yes)
			(effects
				(font
					(size 1.27 1.27)
				)
			)
		)
		(property "Value" ""
			(at 0 0 0)
			(layer "F.Fab")
			(effects
				(font
					(size 1.27 1.27)
				)
			)
		)
		(duplicate_pad_numbers_are_jumpers no)
		(fp_line
			(start -0.7874 -0.4064)
			(end 0.7874 -0.4064)
			(stroke
				(width 0.1524)
				(type default)
			)
			(layer "F.SilkS")
		)
		(fp_line
			(start -0.7874 0.4064)
			(end -0.7874 -0.4064)
			(stroke
				(width 0.1524)
				(type default)
			)
			(layer "F.SilkS")
		)
		(fp_line
			(start 0.7874 -0.4064)
			(end 0.7874 0.4064)
			(stroke
				(width 0.1524)
				(type default)
			)
			(layer "F.SilkS")
		)
		(fp_line
			(start 0.7874 0.4064)
			(end -0.7874 0.4064)
			(stroke
				(width 0.1524)
				(type default)
			)
			(layer "F.SilkS")
		)
		(fp_line
			(start -0.67945 -0.305054)
			(end -0.12065 -0.305054)
			(stroke
				(width 0.1)
				(type default)
			)
			(layer "F.Fab")
		)
		(fp_line
			(start -0.67945 0.3048)
			(end -0.67945 -0.305054)
			(stroke
				(width 0.1)
				(type default)
			)
			(layer "F.Fab")
		)
		(fp_line
			(start -0.12065 -0.305054)
			(end -0.12065 -0.2794)
			(stroke
				(width 0.1)
				(type default)
			)
			(layer "F.Fab")
		)
		(fp_line
			(start -0.12065 -0.2794)
			(end 0.12065 -0.2794)
			(stroke
				(width 0.1)
				(type default)
			)
			(layer "F.Fab")
		)
		(fp_line
			(start -0.12065 0.2794)
			(end -0.12065 0.3048)
			(stroke
				(width 0.1)
				(type default)
			)
			(layer "F.Fab")
		)
		(fp_line
			(start -0.12065 0.3048)
			(end -0.67945 0.3048)
			(stroke
				(width 0.1)
				(type default)
			)
			(layer "F.Fab")
		)
		(fp_line
			(start 0.120396 0.2794)
			(end -0.12065 0.2794)
			(stroke
				(width 0.1)
				(type default)
			)
			(layer "F.Fab")
		)
		(fp_line
			(start 0.120396 0.3048)
			(end 0.120396 0.2794)
			(stroke
				(width 0.1)
				(type default)
			)
			(layer "F.Fab")
		)
		(fp_line
			(start 0.12065 -0.3048)
			(end 0.67945 -0.3048)
			(stroke
				(width 0.1)
				(type default)
			)
			(layer "F.Fab")
		)
		(fp_line
			(start 0.12065 -0.2794)
			(end 0.12065 -0.3048)
			(stroke
				(width 0.1)
				(type default)
			)
			(layer "F.Fab")
		)
		(fp_line
			(start 0.67945 -0.3048)
			(end 0.67945 0.3048)
			(stroke
				(width 0.1)
				(type default)
			)
			(layer "F.Fab")
		)
		(fp_line
			(start 0.67945 0.3048)
			(end 0.120396 0.3048)
			(stroke
				(width 0.1)
				(type default)
			)
			(layer "F.Fab")
		)
		(pad "1" smd circle
			(at -0.40005 0)
			(size 0 0)
			(layers "F.Cu" "F.Mask" "F.Paste")
			(net "HP_LVC3_OCP_V3_2_PRSNT2_N_R")
		)
		(pad "2" smd circle
			(at 0.40005 0)
			(size 0 0)
			(layers "F.Cu" "F.Mask" "F.Paste")
			(net "HP_LVC3_OCP_V3_2_PRSNT2_N")
		)
	)
)
